(kicad_pcb
	(version 20260206)
	(generator "pcbnew")
	(generator_version "10.0")
	(general
		(thickness 1.6)
		(legacy_teardrops no)
	)
	(paper "A4")
	(title_block
		(title "Wiwynn_Tioga_Pass_MB.brd")
		(comment 1 "Tioga Pass / footprint 587 of 4770 (J6E1), pads 1-122 of 122")
	)
	(layers
		(0 "F.Cu" signal "TOP")
		(4 "In1.Cu" signal "L2GND")
		(6 "In2.Cu" signal "L3")
		(8 "In3.Cu" signal "L4GND")
		(10 "In4.Cu" signal "L5")
		(12 "In5.Cu" signal "L6GND")
		(14 "In6.Cu" signal "L7VCC")
		(16 "In7.Cu" signal "L8VCC")
		(18 "In8.Cu" signal "L9GND")
		(20 "In9.Cu" signal "L10")
		(22 "In10.Cu" signal "L11GND")
		(24 "In11.Cu" signal "L12")
		(26 "In12.Cu" signal "L13GND")
		(2 "B.Cu" signal "BOTTOM")
		(9 "F.Adhes" user "F.Adhesive")
		(11 "B.Adhes" user "B.Adhesive")
		(13 "F.Paste" user "Package Geometry/Pastemask Top")
		(15 "B.Paste" user "Package Geometry/Pastemask Bottom")
		(5 "F.SilkS" user "Ref Des/Silkscreen Top")
		(7 "B.SilkS" user "Ref Des/Silkscreen Bottom")
		(1 "F.Mask" user "Board Geometry/Soldermask Top")
		(3 "B.Mask" user "Board Geometry/Soldermask Bottom")
		(17 "Dwgs.User" user "User.Drawings")
		(19 "Cmts.User" user "User.Comments")
		(21 "Eco1.User" user "User.Eco1")
		(23 "Eco2.User" user "User.Eco2")
		(25 "Edge.Cuts" user "Board Geometry/Outline")
		(27 "Margin" user)
		(31 "F.CrtYd" user "Package Geometry/Place Bound Top")
		(29 "B.CrtYd" user "Package Geometry/Place Bound Bottom")
		(35 "F.Fab" user "Ref Des/Assembly Top")
		(33 "B.Fab" user "Ref Des/Assembly Bottom")
	)
	(footprint ""
		(layer "F.Cu")
		(at 329.594972 -43.80103 90)
		(property "Reference" "J6E1"
			(at -3.59283 -5.018024 90)
			(unlocked yes)
			(layer "F.SilkS")
			(effects
				(font
					(size 0.7874 0.5842)
					(thickness 0.1524)
				)
			)
		)
		(property "Value" ""
			(at 0 0 90)
			(layer "F.Fab")
			(effects
				(font
					(size 1.27 1.27)
				)
			)
		)
		(duplicate_pad_numbers_are_jumpers no)
		(pad "" np_thru_hole circle
			(at -3.175 26.5557 90)
			(size 0.254 0.254)
			(drill 1.27)
			(layers "*.Cu" "*.Mask")
			(clearance 0.8255)
			(thermal_gap 0.8255)
		)
		(pad "" np_thru_hole circle
			(at -0.127 -2.4257 90)
			(size 0.254 0.254)
			(drill 1.27)
			(layers "*.Cu" "*.Mask")
			(clearance 0.8255)
			(thermal_gap 0.8255)
		)
		(pad "A1" smd circle
			(at 0 0 90)
			(size 0.635 0.635)
			(layers "F.Cu" "F.Mask" "F.Paste")
			(net "PVCCMCP_CPU0")
		)
		(pad "A2" smd circle
			(at 0 1.27 90)
			(size 0.635 0.635)
			(layers "F.Cu" "F.Mask" "F.Paste")
			(net "PVCCMCP_CPU0")
		)
		(pad "A3" smd circle
			(at 0 2.54 90)
			(size 0.635 0.635)
			(layers "F.Cu" "F.Mask" "F.Paste")
			(net "PVCCMCP_CPU0")
		)
		(pad "A4" smd circle
			(at 0 3.81 90)
			(size 0.635 0.635)
			(layers "F.Cu" "F.Mask" "F.Paste")
			(net "VSENSE_PVCCMCP_CPU0_SKT_VSEN")
		)
		(pad "A5" smd circle
			(at 0 5.08 90)
			(size 0.635 0.635)
			(layers "F.Cu" "F.Mask" "F.Paste")
			(net "PVCCMCP_CPU0")
		)
		(pad "A6" smd circle
			(at 0 6.35 90)
			(size 0.635 0.635)
			(layers "F.Cu" "F.Mask" "F.Paste")
			(net "PVCCMCP_CPU0")
		)
		(pad "A7" smd circle
			(at 0 7.62 90)
			(size 0.635 0.635)
			(layers "F.Cu" "F.Mask" "F.Paste")
			(net "PVCCMCP_CPU0")
		)
		(pad "A8" smd circle
			(at 0 8.89 90)
			(size 0.635 0.635)
			(layers "F.Cu" "F.Mask" "F.Paste")
			(net "PVCCMCP_CPU0")
		)
		(pad "A9" smd circle
			(at 0 10.16 90)
			(size 0.635 0.635)
			(layers "F.Cu" "F.Mask" "F.Paste")
			(net "PVCCMCP_CPU0")
		)
		(pad "A10" smd circle
			(at 0 11.43 90)
			(size 0.635 0.635)
			(layers "F.Cu" "F.Mask" "F.Paste")
			(net "PVCCMCP_CPU0")
		)
		(pad "A11" smd circle
			(at 0 12.7 90)
			(size 0.635 0.635)
			(layers "F.Cu" "F.Mask" "F.Paste")
			(net "PVCCMCP_CPU0")
		)
		(pad "A12" smd circle
			(at 0 13.97 90)
			(size 0.635 0.635)
			(layers "F.Cu" "F.Mask" "F.Paste")
			(net "PVCCMCP_CPU0")
		)
		(pad "A13" smd circle
			(at 0 15.24 90)
			(size 0.635 0.635)
			(layers "F.Cu" "F.Mask" "F.Paste")
			(net "PVCCMCP_CPU0")
		)
		(pad "A14" smd circle
			(at 0 16.51 90)
			(size 0.635 0.635)
			(layers "F.Cu" "F.Mask" "F.Paste")
			(net "PVCCMCP_CPU0")
		)
		(pad "A15" smd circle
			(at 0 17.78 90)
			(size 0.635 0.635)
			(layers "F.Cu" "F.Mask" "F.Paste")
			(net "PVCCMCP_CPU0")
		)
		(pad "A16" smd circle
			(at 0 19.05 90)
			(size 0.635 0.635)
			(layers "F.Cu" "F.Mask" "F.Paste")
			(net "PVCCMCP_CPU0")
		)
		(pad "A17" smd circle
			(at 0 20.32 90)
			(size 0.635 0.635)
			(layers "F.Cu" "F.Mask" "F.Paste")
			(net "PVCCMCP_CPU0")
		)
		(pad "A18" smd circle
			(at 0 21.59 90)
			(size 0.635 0.635)
			(layers "F.Cu" "F.Mask" "F.Paste")
			(net "PVCCMCP_CPU0")
		)
		(pad "A19" smd circle
			(at 0 22.86 90)
			(size 0.635 0.635)
			(layers "F.Cu" "F.Mask" "F.Paste")
			(net "GND")
		)
		(pad "A20" smd circle
			(at 0 24.13 90)
			(size 0.635 0.635)
			(layers "F.Cu" "F.Mask" "F.Paste")
			(net "GND")
		)
		(pad "B1" smd circle
			(at -1.27 0 90)
			(size 0.635 0.635)
			(layers "F.Cu" "F.Mask" "F.Paste")
			(net "PVCCMCP_CPU0")
		)
		(pad "B2" smd circle
			(at -1.27 1.27 90)
			(size 0.635 0.635)
			(layers "F.Cu" "F.Mask" "F.Paste")
			(net "PVCCMCP_CPU0")
		)
		(pad "B3" smd circle
			(at -1.27 2.54 90)
			(size 0.635 0.635)
			(layers "F.Cu" "F.Mask" "F.Paste")
			(net "PVCCMCP_CPU0")
		)
		(pad "B4" smd circle
			(at -1.27 3.81 90)
			(size 0.635 0.635)
			(layers "F.Cu" "F.Mask" "F.Paste")
			(net "VSENSE_PVCCMCP_CPU0_SKT_VRTN")
		)
		(pad "B5" smd circle
			(at -1.27 5.08 90)
			(size 0.635 0.635)
			(layers "F.Cu" "F.Mask" "F.Paste")
			(net "PVCCMCP_CPU0")
		)
		(pad "B6" smd circle
			(at -1.27 6.35 90)
			(size 0.635 0.635)
			(layers "F.Cu" "F.Mask" "F.Paste")
			(net "PVCCMCP_CPU0")
		)
		(pad "B7" smd circle
			(at -1.27 7.62 90)
			(size 0.635 0.635)
			(layers "F.Cu" "F.Mask" "F.Paste")
			(net "PVCCMCP_CPU0")
		)
		(pad "B8" smd circle
			(at -1.27 8.89 90)
			(size 0.635 0.635)
			(layers "F.Cu" "F.Mask" "F.Paste")
			(net "PVCCMCP_CPU0")
		)
		(pad "B9" smd circle
			(at -1.27 10.16 90)
			(size 0.635 0.635)
			(layers "F.Cu" "F.Mask" "F.Paste")
			(net "PVCCMCP_CPU0")
		)
		(pad "B10" smd circle
			(at -1.27 11.43 90)
			(size 0.635 0.635)
			(layers "F.Cu" "F.Mask" "F.Paste")
			(net "PVCCMCP_CPU0")
		)
		(pad "B11" smd circle
			(at -1.27 12.7 90)
			(size 0.635 0.635)
			(layers "F.Cu" "F.Mask" "F.Paste")
			(net "PVCCMCP_CPU0")
		)
		(pad "B12" smd circle
			(at -1.27 13.97 90)
			(size 0.635 0.635)
			(layers "F.Cu" "F.Mask" "F.Paste")
			(net "PVCCMCP_CPU0")
		)
		(pad "B13" smd circle
			(at -1.27 15.24 90)
			(size 0.635 0.635)
			(layers "F.Cu" "F.Mask" "F.Paste")
			(net "PVCCMCP_CPU0")
		)
		(pad "B14" smd circle
			(at -1.27 16.51 90)
			(size 0.635 0.635)
			(layers "F.Cu" "F.Mask" "F.Paste")
			(net "PVCCMCP_CPU0")
		)
		(pad "B15" smd circle
			(at -1.27 17.78 90)
			(size 0.635 0.635)
			(layers "F.Cu" "F.Mask" "F.Paste")
			(net "PVCCMCP_CPU0")
		)
		(pad "B16" smd circle
			(at -1.27 19.05 90)
			(size 0.635 0.635)
			(layers "F.Cu" "F.Mask" "F.Paste")
			(net "PVCCMCP_CPU0")
		)
		(pad "B17" smd circle
			(at -1.27 20.32 90)
			(size 0.635 0.635)
			(layers "F.Cu" "F.Mask" "F.Paste")
			(net "PVCCMCP_CPU0")
		)
		(pad "B18" smd circle
			(at -1.27 21.59 90)
			(size 0.635 0.635)
			(layers "F.Cu" "F.Mask" "F.Paste")
			(net "PVCCMCP_CPU0")
		)
		(pad "B19" smd circle
			(at -1.27 22.86 90)
			(size 0.635 0.635)
			(layers "F.Cu" "F.Mask" "F.Paste")
			(net "GND")
		)
		(pad "B20" smd circle
			(at -1.27 24.13 90)
			(size 0.635 0.635)
			(layers "F.Cu" "F.Mask" "F.Paste")
			(net "GND")
		)
		(pad "C1" smd circle
			(at -2.54 0 90)
			(size 0.635 0.635)
			(layers "F.Cu" "F.Mask" "F.Paste")
			(net "PVCCMCP_CPU0")
		)
		(pad "C2" smd circle
			(at -2.54 1.27 90)
			(size 0.635 0.635)
			(layers "F.Cu" "F.Mask" "F.Paste")
			(net "PVCCMCP_CPU0")
		)
		(pad "C3" smd circle
			(at -2.54 2.54 90)
			(size 0.635 0.635)
			(layers "F.Cu" "F.Mask" "F.Paste")
			(net "PVCCMCP_CPU0")
		)
		(pad "C4" smd circle
			(at -2.54 3.81 90)
			(size 0.635 0.635)
			(layers "F.Cu" "F.Mask" "F.Paste")
			(net "PVCCMCP_CPU0")
		)
		(pad "C5" smd circle
			(at -2.54 5.08 90)
			(size 0.635 0.635)
			(layers "F.Cu" "F.Mask" "F.Paste")
			(net "PVCCMCP_CPU0")
		)
		(pad "C6" smd circle
			(at -2.54 6.35 90)
			(size 0.635 0.635)
			(layers "F.Cu" "F.Mask" "F.Paste")
			(net "PVCCMCP_CPU0")
		)
		(pad "C7" smd circle
			(at -2.54 7.62 90)
			(size 0.635 0.635)
			(layers "F.Cu" "F.Mask" "F.Paste")
			(net "PVCCMCP_CPU0")
		)
		(pad "C8" smd circle
			(at -2.54 8.89 90)
			(size 0.635 0.635)
			(layers "F.Cu" "F.Mask" "F.Paste")
			(net "PVCCMCP_CPU0")
		)
		(pad "C9" smd circle
			(at -2.54 10.16 90)
			(size 0.635 0.635)
			(layers "F.Cu" "F.Mask" "F.Paste")
			(net "PVCCMCP_CPU0")
		)
		(pad "C10" smd circle
			(at -2.54 11.43 90)
			(size 0.635 0.635)
			(layers "F.Cu" "F.Mask" "F.Paste")
			(net "PVCCMCP_CPU0")
		)
		(pad "C11" smd circle
			(at -2.54 12.7 90)
			(size 0.635 0.635)
			(layers "F.Cu" "F.Mask" "F.Paste")
			(net "PVCCMCP_CPU0")
		)
		(pad "C12" smd circle
			(at -2.54 13.97 90)
			(size 0.635 0.635)
			(layers "F.Cu" "F.Mask" "F.Paste")
			(net "PVCCMCP_CPU0")
		)
		(pad "C13" smd circle
			(at -2.54 15.24 90)
			(size 0.635 0.635)
			(layers "F.Cu" "F.Mask" "F.Paste")
			(net "PVCCMCP_CPU0")
		)
		(pad "C14" smd circle
			(at -2.54 16.51 90)
			(size 0.635 0.635)
			(layers "F.Cu" "F.Mask" "F.Paste")
			(net "PVCCMCP_CPU0")
		)
		(pad "C15" smd circle
			(at -2.54 17.78 90)
			(size 0.635 0.635)
			(layers "F.Cu" "F.Mask" "F.Paste")
			(net "PVCCMCP_CPU0")
		)
		(pad "C16" smd circle
			(at -2.54 19.05 90)
			(size 0.635 0.635)
			(layers "F.Cu" "F.Mask" "F.Paste")
			(net "PVCCMCP_CPU0")
		)
		(pad "C17" smd circle
			(at -2.54 20.32 90)
			(size 0.635 0.635)
			(layers "F.Cu" "F.Mask" "F.Paste")
			(net "PVCCMCP_CPU0")
		)
		(pad "C18" smd circle
			(at -2.54 21.59 90)
			(size 0.635 0.635)
			(layers "F.Cu" "F.Mask" "F.Paste")
			(net "PVCCMCP_CPU0")
		)
		(pad "C19" smd circle
			(at -2.54 22.86 90)
			(size 0.635 0.635)
			(layers "F.Cu" "F.Mask" "F.Paste")
			(net "GND")
		)
		(pad "C20" smd circle
			(at -2.54 24.13 90)
			(size 0.635 0.635)
			(layers "F.Cu" "F.Mask" "F.Paste")
			(net "GND")
		)
		(pad "D1" smd circle
			(at -3.81 0 90)
			(size 0.635 0.635)
			(layers "F.Cu" "F.Mask" "F.Paste")
			(net "VSENSE_P1V8MCP_CPU0_SKT_VSEN")
		)
		(pad "D2" smd circle
			(at -3.81 1.27 90)
			(size 0.635 0.635)
			(layers "F.Cu" "F.Mask" "F.Paste")
			(net "VSENSE_P1V8MCP_CPU0_SKT_VRTN")
		)
		(pad "D3" smd circle
			(at -3.81 2.54 90)
			(size 0.635 0.635)
			(layers "F.Cu" "F.Mask" "F.Paste")
			(net "P1V8_MCP_CPU0")
		)
		(pad "D4" smd circle
			(at -3.81 3.81 90)
			(size 0.635 0.635)
			(layers "F.Cu" "F.Mask" "F.Paste")
			(net "GND")
		)
		(pad "D5" smd circle
			(at -3.81 5.08 90)
			(size 0.635 0.635)
			(layers "F.Cu" "F.Mask" "F.Paste")
			(net "GND")
		)
		(pad "D6" smd circle
			(at -3.81 6.35 90)
			(size 0.635 0.635)
			(layers "F.Cu" "F.Mask" "F.Paste")
			(net "GND")
		)
		(pad "D7" smd circle
			(at -3.81 7.62 90)
			(size 0.635 0.635)
			(layers "F.Cu" "F.Mask" "F.Paste")
			(net "GND")
		)
		(pad "D8" smd circle
			(at -3.81 8.89 90)
			(size 0.635 0.635)
			(layers "F.Cu" "F.Mask" "F.Paste")
			(net "GND")
		)
		(pad "D9" smd circle
			(at -3.81 10.16 90)
			(size 0.635 0.635)
			(layers "F.Cu" "F.Mask" "F.Paste")
			(net "GND")
		)
		(pad "D10" smd circle
			(at -3.81 11.43 90)
			(size 0.635 0.635)
			(layers "F.Cu" "F.Mask" "F.Paste")
			(net "GND")
		)
		(pad "D11" smd circle
			(at -3.81 12.7 90)
			(size 0.635 0.635)
			(layers "F.Cu" "F.Mask" "F.Paste")
			(net "GND")
		)
		(pad "D12" smd circle
			(at -3.81 13.97 90)
			(size 0.635 0.635)
			(layers "F.Cu" "F.Mask" "F.Paste")
			(net "GND")
		)
		(pad "D13" smd circle
			(at -3.81 15.24 90)
			(size 0.635 0.635)
			(layers "F.Cu" "F.Mask" "F.Paste")
			(net "GND")
		)
		(pad "D14" smd circle
			(at -3.81 16.51 90)
			(size 0.635 0.635)
			(layers "F.Cu" "F.Mask" "F.Paste")
			(net "GND")
		)
		(pad "D15" smd circle
			(at -3.81 17.78 90)
			(size 0.635 0.635)
			(layers "F.Cu" "F.Mask" "F.Paste")
			(net "GND")
		)
		(pad "D16" smd circle
			(at -3.81 19.05 90)
			(size 0.635 0.635)
			(layers "F.Cu" "F.Mask" "F.Paste")
			(net "GND")
		)
		(pad "D17" smd circle
			(at -3.81 20.32 90)
			(size 0.635 0.635)
			(layers "F.Cu" "F.Mask" "F.Paste")
			(net "GND")
		)
		(pad "D18" smd circle
			(at -3.81 21.59 90)
			(size 0.635 0.635)
			(layers "F.Cu" "F.Mask" "F.Paste")
			(net "GND")
		)
		(pad "D19" smd circle
			(at -3.81 22.86 90)
			(size 0.635 0.635)
			(layers "F.Cu" "F.Mask" "F.Paste")
			(net "GND")
		)
		(pad "D20" smd circle
			(at -3.81 24.13 90)
			(size 0.635 0.635)
			(layers "F.Cu" "F.Mask" "F.Paste")
			(net "GND")
		)
		(pad "E1" smd circle
			(at -5.08 0 90)
			(size 0.635 0.635)
			(layers "F.Cu" "F.Mask" "F.Paste")
			(net "P1V8_MCP_CPU0")
		)
		(pad "E2" smd circle
			(at -5.08 1.27 90)
			(size 0.635 0.635)
			(layers "F.Cu" "F.Mask" "F.Paste")
			(net "P1V8_MCP_CPU0")
		)
		(pad "E3" smd circle
			(at -5.08 2.54 90)
			(size 0.635 0.635)
			(layers "F.Cu" "F.Mask" "F.Paste")
			(net "P1V8_MCP_CPU0")
		)
		(pad "E4" smd circle
			(at -5.08 3.81 90)
			(size 0.635 0.635)
			(layers "F.Cu" "F.Mask" "F.Paste")
			(net "GND")
		)
		(pad "E5" smd circle
			(at -5.08 5.08 90)
			(size 0.635 0.635)
			(layers "F.Cu" "F.Mask" "F.Paste")
			(net "CLK_322M_156M_CPU0_OSC_VRM_DP")
		)
		(pad "E6" smd circle
			(at -5.08 6.35 90)
			(size 0.635 0.635)
			(layers "F.Cu" "F.Mask" "F.Paste")
			(net "GND")
		)
		(pad "E7" smd circle
			(at -5.08 7.62 90)
			(size 0.635 0.635)
			(layers "F.Cu" "F.Mask" "F.Paste")
			(net "GND")
		)
		(pad "E8" smd circle
			(at -5.08 8.89 90)
			(size 0.635 0.635)
			(layers "F.Cu" "F.Mask" "F.Paste")
			(net "GND")
		)
		(pad "E9" smd circle
			(at -5.08 10.16 90)
			(size 0.635 0.635)
			(layers "F.Cu" "F.Mask" "F.Paste")
			(net "GND")
		)
		(pad "E10" smd circle
			(at -5.08 11.43 90)
			(size 0.635 0.635)
			(layers "F.Cu" "F.Mask" "F.Paste")
			(net "GND")
		)
		(pad "E11" smd circle
			(at -5.08 12.7 90)
			(size 0.635 0.635)
			(layers "F.Cu" "F.Mask" "F.Paste")
			(net "GND")
		)
		(pad "E12" smd circle
			(at -5.08 13.97 90)
			(size 0.635 0.635)
			(layers "F.Cu" "F.Mask" "F.Paste")
			(net "GND")
		)
		(pad "E13" smd circle
			(at -5.08 15.24 90)
			(size 0.635 0.635)
			(layers "F.Cu" "F.Mask" "F.Paste")
			(net "GND")
		)
		(pad "E14" smd circle
			(at -5.08 16.51 90)
			(size 0.635 0.635)
			(layers "F.Cu" "F.Mask" "F.Paste")
			(net "GND")
		)
		(pad "E15" smd circle
			(at -5.08 17.78 90)
			(size 0.635 0.635)
			(layers "F.Cu" "F.Mask" "F.Paste")
			(net "GND")
		)
		(pad "E16" smd circle
			(at -5.08 19.05 90)
			(size 0.635 0.635)
			(layers "F.Cu" "F.Mask" "F.Paste")
			(net "GND")
		)
		(pad "E17" smd circle
			(at -5.08 20.32 90)
			(size 0.635 0.635)
			(layers "F.Cu" "F.Mask" "F.Paste")
			(net "GND")
		)
		(pad "E18" smd circle
			(at -5.08 21.59 90)
			(size 0.635 0.635)
			(layers "F.Cu" "F.Mask" "F.Paste")
			(net "GND")
		)
		(pad "E19" smd circle
			(at -5.08 22.86 90)
			(size 0.635 0.635)
			(layers "F.Cu" "F.Mask" "F.Paste")
			(net "GND")
		)
		(pad "E20" smd circle
			(at -5.08 24.13 90)
			(size 0.635 0.635)
			(layers "F.Cu" "F.Mask" "F.Paste")
			(net "GND")
		)
		(pad "F1" smd circle
			(at -6.35 0 90)
			(size 0.635 0.635)
			(layers "F.Cu" "F.Mask" "F.Paste")
			(net "P1V8_MCP_CPU0")
		)
		(pad "F2" smd circle
			(at -6.35 1.27 90)
			(size 0.635 0.635)
			(layers "F.Cu" "F.Mask" "F.Paste")
			(net "P1V8_MCP_CPU0")
		)
		(pad "F3" smd circle
			(at -6.35 2.54 90)
			(size 0.635 0.635)
			(layers "F.Cu" "F.Mask" "F.Paste")
			(net "P1V8_MCP_CPU0")
		)
		(pad "F4" smd circle
			(at -6.35 3.81 90)
			(size 0.635 0.635)
			(layers "F.Cu" "F.Mask" "F.Paste")
			(net "GND")
		)
		(pad "F5" smd circle
			(at -6.35 5.08 90)
			(size 0.635 0.635)
			(layers "F.Cu" "F.Mask" "F.Paste")
			(net "CLK_322M_156M_CPU0_OSC_VRM_DN")
		)
		(pad "F6" smd circle
			(at -6.35 6.35 90)
			(size 0.635 0.635)
			(layers "F.Cu" "F.Mask" "F.Paste")
			(net "GND")
		)
		(pad "F7" smd circle
			(at -6.35 7.62 90)
			(size 0.635 0.635)
			(layers "F.Cu" "F.Mask" "F.Paste")
			(net "GND")
		)
		(pad "F8" smd circle
			(at -6.35 8.89 90)
			(size 0.635 0.635)
			(layers "F.Cu" "F.Mask" "F.Paste")
			(net "GND")
		)
		(pad "F9" smd circle
			(at -6.35 10.16 90)
			(size 0.635 0.635)
			(layers "F.Cu" "F.Mask" "F.Paste")
			(net "GND")
		)
		(pad "F10" smd circle
			(at -6.35 11.43 90)
			(size 0.635 0.635)
			(layers "F.Cu" "F.Mask" "F.Paste")
			(net "GND")
		)
		(pad "F11" smd circle
			(at -6.35 12.7 90)
			(size 0.635 0.635)
			(layers "F.Cu" "F.Mask" "F.Paste")
			(net "GND")
		)
		(pad "F12" smd circle
			(at -6.35 13.97 90)
			(size 0.635 0.635)
			(layers "F.Cu" "F.Mask" "F.Paste")
			(net "GND")
		)
		(pad "F13" smd circle
			(at -6.35 15.24 90)
			(size 0.635 0.635)
			(layers "F.Cu" "F.Mask" "F.Paste")
			(net "GND")
		)
		(pad "F14" smd circle
			(at -6.35 16.51 90)
			(size 0.635 0.635)
			(layers "F.Cu" "F.Mask" "F.Paste")
			(net "GND")
		)
		(pad "F15" smd circle
			(at -6.35 17.78 90)
			(size 0.635 0.635)
			(layers "F.Cu" "F.Mask" "F.Paste")
			(net "GND")
		)
		(pad "F16" smd circle
			(at -6.35 19.05 90)
			(size 0.635 0.635)
			(layers "F.Cu" "F.Mask" "F.Paste")
			(net "GND")
		)
		(pad "F17" smd circle
			(at -6.35 20.32 90)
			(size 0.635 0.635)
			(layers "F.Cu" "F.Mask" "F.Paste")
			(net "GND")
		)
		(pad "F18" smd circle
			(at -6.35 21.59 90)
			(size 0.635 0.635)
			(layers "F.Cu" "F.Mask" "F.Paste")
			(net "GND")
		)
		(pad "F19" smd circle
			(at -6.35 22.86 90)
			(size 0.635 0.635)
			(layers "F.Cu" "F.Mask" "F.Paste")
			(net "GND")
		)
		(pad "F20" smd circle
			(at -6.35 24.13 90)
			(size 0.635 0.635)
			(layers "F.Cu" "F.Mask" "F.Paste")
			(net "GND")
		)
	)
)
